# T6G (Grand Teton) — schematic netlist excerpt (pin names and nets, part order shuffled) for the footprints in the layout excerpt that follows; sources: Cadence DE-HDL packaged netlist, KiCad conversion of 04192023_DAF0TMB3IC0_F0TG_MB_C_brd_V02_OCP.brd

C476  Q_CAP  22UF 4V 20% X6S  pkg C0402  page 356 : A = P0V9_CPU1_RT3_2A ; B = GND
PC102  Q_CAPP  220UF 4V 20% SPCAP  pkg SMLF  page 201 : A = PVDDCR_CPU1_P0 ; B = GND

(kicad_pcb
	(version 20260206)
	(generator "pcbnew")
	(generator_version "10.0")
	(general
		(thickness 1.6)
		(legacy_teardrops no)
	)
	(paper "A4")
	(title_block
		(title "04192023_DAF0TMB3IC0_F0TG_MB_C_brd_V02_OCP.brd")
		(comment 1 "Grand Teton / footprints 6231-6232 of 8354")
	)
	(layers
		(0 "F.Cu" signal "TOP")
		(4 "In1.Cu" signal "GND")
		(6 "In2.Cu" signal "IN1")
		(8 "In3.Cu" signal "GND1")
		(10 "In4.Cu" signal "IN2")
		(12 "In5.Cu" signal "GND2")
		(14 "In6.Cu" signal "IN3")
		(16 "In7.Cu" signal "GND3")
		(18 "In8.Cu" signal "VCC")
		(20 "In9.Cu" signal "VCC1")
		(22 "In10.Cu" signal "GND4")
		(24 "In11.Cu" signal "IN4")
		(26 "In12.Cu" signal "GND5")
		(28 "In13.Cu" signal "IN5")
		(30 "In14.Cu" signal "GND6")
		(32 "In15.Cu" signal "IN6")
		(34 "In16.Cu" signal "GND7")
		(2 "B.Cu" signal "BOTTOM")
		(9 "F.Adhes" user "F.Adhesive")
		(11 "B.Adhes" user "B.Adhesive")
		(13 "F.Paste" user "Package Geometry/Pastemask Top")
		(15 "B.Paste" user "Package Geometry/Pastemask Bottom")
		(5 "F.SilkS" user "Ref Des/Silkscreen Top")
		(7 "B.SilkS" user "Ref Des/Silkscreen Bottom")
		(1 "F.Mask" user "Board Geometry/Soldermask Top")
		(3 "B.Mask" user "Board Geometry/Soldermask Bottom")
		(17 "Dwgs.User" user "User.Drawings")
		(19 "Cmts.User" user "User.Comments")
		(21 "Eco1.User" user "User.Eco1")
		(23 "Eco2.User" user "User.Eco2")
		(25 "Edge.Cuts" user "Board Geometry/Outline")
		(27 "Margin" user)
		(31 "F.CrtYd" user "Package Geometry/Place Bound Top")
		(29 "B.CrtYd" user "Package Geometry/Place Bound Bottom")
		(35 "F.Fab" user "Ref Des/Assembly Top")
		(33 "B.Fab" user "Ref Des/Assembly Bottom")
	)
	(footprint ""
		(layer "B.Cu")
		(at 115.691158 -390.560052 90)
		(property "Reference" "C476"
			(at 0 0 90)
			(layer "B.SilkS")
			(hide yes)
			(effects
				(font
					(size 1.27 1.27)
				)
				(justify mirror)
			)
		)
		(property "Value" ""
			(at 0 0 90)
			(layer "B.Fab")
			(effects
				(font
					(size 1.27 1.27)
				)
				(justify mirror)
			)
		)
		(duplicate_pad_numbers_are_jumpers no)
		(fp_line
			(start 0.7874 -0.4064)
			(end -0.7874 -0.4064)
			(stroke
				(width 0.1524)
				(type default)
			)
			(layer "B.SilkS")
		)
		(fp_line
			(start -0.7874 -0.4064)
			(end -0.7874 0.4064)
			(stroke
				(width 0.1524)
				(type default)
			)
			(layer "B.SilkS")
		)
		(fp_line
			(start 0.7874 0.4064)
			(end 0.7874 -0.4064)
			(stroke
				(width 0.1524)
				(type default)
			)
			(layer "B.SilkS")
		)
		(fp_line
			(start -0.7874 0.4064)
			(end 0.7874 0.4064)
			(stroke
				(width 0.1524)
				(type default)
			)
			(layer "B.SilkS")
		)
		(fp_line
			(start 0.67945 -0.305054)
			(end 0.12065 -0.305054)
			(stroke
				(width 0.1)
				(type default)
			)
			(layer "B.Fab")
		)
		(fp_line
			(start 0.12065 -0.305054)
			(end 0.12065 -0.2794)
			(stroke
				(width 0.1)
				(type default)
			)
			(layer "B.Fab")
		)
		(fp_line
			(start -0.12065 -0.3048)
			(end -0.67945 -0.3048)
			(stroke
				(width 0.1)
				(type default)
			)
			(layer "B.Fab")
		)
		(fp_line
			(start -0.67945 -0.3048)
			(end -0.67945 0.3048)
			(stroke
				(width 0.1)
				(type default)
			)
			(layer "B.Fab")
		)
		(fp_line
			(start 0.12065 -0.2794)
			(end -0.12065 -0.2794)
			(stroke
				(width 0.1)
				(type default)
			)
			(layer "B.Fab")
		)
		(fp_line
			(start -0.12065 -0.2794)
			(end -0.12065 -0.3048)
			(stroke
				(width 0.1)
				(type default)
			)
			(layer "B.Fab")
		)
		(fp_line
			(start 0.12065 0.2794)
			(end 0.12065 0.3048)
			(stroke
				(width 0.1)
				(type default)
			)
			(layer "B.Fab")
		)
		(fp_line
			(start -0.120396 0.2794)
			(end 0.12065 0.2794)
			(stroke
				(width 0.1)
				(type default)
			)
			(layer "B.Fab")
		)
		(fp_line
			(start 0.67945 0.3048)
			(end 0.67945 -0.305054)
			(stroke
				(width 0.1)
				(type default)
			)
			(layer "B.Fab")
		)
		(fp_line
			(start 0.12065 0.3048)
			(end 0.67945 0.3048)
			(stroke
				(width 0.1)
				(type default)
			)
			(layer "B.Fab")
		)
		(fp_line
			(start -0.120396 0.3048)
			(end -0.120396 0.2794)
			(stroke
				(width 0.1)
				(type default)
			)
			(layer "B.Fab")
		)
		(fp_line
			(start -0.67945 0.3048)
			(end -0.120396 0.3048)
			(stroke
				(width 0.1)
				(type default)
			)
			(layer "B.Fab")
		)
		(pad "1" smd circle
			(at 0.40005 0 270)
			(size 0 0)
			(layers "B.Cu" "B.Mask" "B.Paste")
			(net "P0V9_CPU1_RT3_2A")
		)
		(pad "2" smd circle
			(at -0.40005 0 270)
			(size 0 0)
			(layers "B.Cu" "B.Mask" "B.Paste")
			(net "GND")
		)
	)
	(footprint ""
		(layer "B.Cu")
		(at 325.910448 -328.240644 -90)
		(property "Reference" "PC102"
			(at 10.105644 -1.341882 270)
			(unlocked yes)
			(layer "B.SilkS")
			(effects
				(font
					(size 0.7874 0.5842)
					(thickness 0.1524)
				)
				(justify left mirror)
			)
		)
		(property "Value" ""
			(at 0 0 90)
			(layer "B.Fab")
			(effects
				(font
					(size 1.27 1.27)
				)
				(justify mirror)
			)
		)
		(duplicate_pad_numbers_are_jumpers no)
		(fp_line
			(start -4.533392 2.249932)
			(end 4.533392 2.249932)
			(stroke
				(width 0.1524)
				(type default)
			)
			(layer "B.SilkS")
		)
		(fp_line
			(start 4.533392 2.249932)
			(end 4.533392 -2.249932)
			(stroke
				(width 0.1524)
				(type default)
			)
			(layer "B.SilkS")
		)
		(fp_line
			(start -4.533392 -2.249932)
			(end -4.533392 2.249932)
			(stroke
				(width 0.1524)
				(type default)
			)
			(layer "B.SilkS")
		)
		(fp_line
			(start 4.533392 -2.249932)
			(end -4.533392 -2.249932)
			(stroke
				(width 0.1524)
				(type default)
			)
			(layer "B.SilkS")
		)
		(fp_rect
			(start 5.39242 2.326132)
			(end 4.533392 -2.326132)
			(stroke
				(width 0)
				(type default)
			)
			(fill yes)
			(layer "B.SilkS")
		)
		(fp_line
			(start -3.750056 2.249932)
			(end 3.750056 2.249932)
			(stroke
				(width 0.1)
				(type default)
			)
			(layer "B.Fab")
		)
		(fp_line
			(start 3.750056 2.249932)
			(end 3.750056 -2.249932)
			(stroke
				(width 0.1)
				(type default)
			)
			(layer "B.Fab")
		)
		(fp_line
			(start -3.750056 -2.249932)
			(end -3.750056 2.249932)
			(stroke
				(width 0.1)
				(type default)
			)
			(layer "B.Fab")
		)
		(fp_line
			(start 3.750056 -2.249932)
			(end -3.750056 -2.249932)
			(stroke
				(width 0.1)
				(type default)
			)
			(layer "B.Fab")
		)
		(fp_text user "+"
			(at 6.294374 0.137922 180)
			(unlocked yes)
			(layer "B.SilkS")
			(effects
				(font
					(size 1.905 1.4224)
					(thickness 0.1524)
				)
				(justify left mirror)
			)
		)
		(fp_text user "-"
			(at -4.8514 -0.14605 270)
			(unlocked yes)
			(layer "B.SilkS")
			(effects
				(font
					(size 1.905 1.4224)
					(thickness 0.1524)
				)
				(justify left mirror)
			)
		)
		(fp_text user "+"
			(at 6.322314 0.786384 180)
			(unlocked yes)
			(layer "B.Fab")
			(effects
				(font
					(size 1.905 1.4224)
					(thickness 0.1524)
				)
				(justify left mirror)
			)
		)
		(fp_text user "-"
			(at -4.8514 -0.14605 270)
			(unlocked yes)
			(layer "B.Fab")
			(effects
				(font
					(size 1.905 1.4224)
					(thickness 0.1524)
				)
				(justify left mirror)
			)
		)
		(pad "1" smd rect
			(at 3.199892 0 90)
			(size 2.413 2.8194)
			(layers "B.Cu" "B.Mask" "B.Paste")
			(net "PVDDCR_CPU1_P0")
		)
		(pad "2" smd rect
			(at -3.199892 0 90)
			(size 2.413 2.8194)
			(layers "B.Cu" "B.Mask" "B.Paste")
			(net "GND")
		)
	)
)
